(kicad_pcb
	(version 20260206)
	(generator "pcbnew")
	(generator_version "10.0")
	(general
		(thickness 1.6)
		(legacy_teardrops no)
	)
	(paper "A4")
	(title_block
		(title "Wiwynn_Tioga_Pass_MB.brd")
		(comment 1 "Tioga Pass / footprints 2646-2653 of 4770")
	)
	(layers
		(0 "F.Cu" signal "TOP")
		(4 "In1.Cu" signal "L2GND")
		(6 "In2.Cu" signal "L3")
		(8 "In3.Cu" signal "L4GND")
		(10 "In4.Cu" signal "L5")
		(12 "In5.Cu" signal "L6GND")
		(14 "In6.Cu" signal "L7VCC")
		(16 "In7.Cu" signal "L8VCC")
		(18 "In8.Cu" signal "L9GND")
		(20 "In9.Cu" signal "L10")
		(22 "In10.Cu" signal "L11GND")
		(24 "In11.Cu" signal "L12")
		(26 "In12.Cu" signal "L13GND")
		(2 "B.Cu" signal "BOTTOM")
		(9 "F.Adhes" user "F.Adhesive")
		(11 "B.Adhes" user "B.Adhesive")
		(13 "F.Paste" user "Package Geometry/Pastemask Top")
		(15 "B.Paste" user "Package Geometry/Pastemask Bottom")
		(5 "F.SilkS" user "Ref Des/Silkscreen Top")
		(7 "B.SilkS" user "Ref Des/Silkscreen Bottom")
		(1 "F.Mask" user "Board Geometry/Soldermask Top")
		(3 "B.Mask" user "Board Geometry/Soldermask Bottom")
		(17 "Dwgs.User" user "User.Drawings")
		(19 "Cmts.User" user "User.Comments")
		(21 "Eco1.User" user "User.Eco1")
		(23 "Eco2.User" user "User.Eco2")
		(25 "Edge.Cuts" user "Board Geometry/Outline")
		(27 "Margin" user)
		(31 "F.CrtYd" user "Package Geometry/Place Bound Top")
		(29 "B.CrtYd" user "Package Geometry/Place Bound Bottom")
		(35 "F.Fab" user "Ref Des/Assembly Top")
		(33 "B.Fab" user "Ref Des/Assembly Bottom")
	)
	(footprint ""
		(layer "B.Cu")
		(at 197.848728 -82.842862 90)
		(property "Reference" "C6P13"
			(at 0 0 90)
			(layer "B.SilkS")
			(hide yes)
			(effects
				(font
					(size 1.27 1.27)
				)
				(justify mirror)
			)
		)
		(property "Value" ""
			(at 0 0 90)
			(layer "B.Fab")
			(effects
				(font
					(size 1.27 1.27)
				)
				(justify mirror)
			)
		)
		(duplicate_pad_numbers_are_jumpers no)
		(fp_rect
			(start 0.7239 1.9939)
			(end -0.7239 -0.2159)
			(stroke
				(width 0)
				(type default)
			)
			(fill no)
			(layer "B.CrtYd")
		)
		(fp_line
			(start 0.7239 -0.2159)
			(end 0.7239 1.9939)
			(stroke
				(width 0.1)
				(type default)
			)
			(layer "B.Fab")
		)
		(fp_line
			(start -0.7239 -0.2159)
			(end 0.7239 -0.2159)
			(stroke
				(width 0.1)
				(type default)
			)
			(layer "B.Fab")
		)
		(fp_line
			(start 0.7239 1.9939)
			(end -0.7239 1.9939)
			(stroke
				(width 0.1)
				(type default)
			)
			(layer "B.Fab")
		)
		(fp_line
			(start -0.7239 1.9939)
			(end -0.7239 -0.2159)
			(stroke
				(width 0.1)
				(type default)
			)
			(layer "B.Fab")
		)
		(pad "1" smd rect
			(at 0 0 270)
			(size 1.27 1.016)
			(layers "B.Cu" "B.Mask" "B.Paste")
			(net "VR_FET_SW_P12V_STBY_PVCCIN_CPU0")
		)
		(pad "2" smd rect
			(at 0 1.778 270)
			(size 1.27 1.016)
			(layers "B.Cu" "B.Mask" "B.Paste")
			(net "GND")
		)
		(zone
			(layer "B.Cu")
			(hatch none 0.5)
			(connect_pads
				(clearance 0)
			)
			(min_thickness 0.25)
			(keepout
				(tracks not_allowed)
				(vias allowed)
				(pads allowed)
				(copperpour not_allowed)
				(footprints allowed)
			)
			(placement
				(enabled no)
				(sheetname "")
			)
			(fill
				(thermal_gap 0.5)
				(thermal_bridge_width 0.5)
				(island_removal_mode 0)
			)
			(polygon
				(pts
					(xy 199.118728 -83.477862) (xy 198.356728 -83.477862) (xy 198.356728 -82.207862) (xy 199.118728 -82.207862)
				)
			)
		)
	)
	(footprint ""
		(layer "B.Cu")
		(at 400.1262 -102.8319)
		(property "Reference" "C7D2"
			(at 0 0 0)
			(layer "B.SilkS")
			(hide yes)
			(effects
				(font
					(size 1.27 1.27)
				)
				(justify mirror)
			)
		)
		(property "Value" ""
			(at 0 0 0)
			(layer "B.Fab")
			(effects
				(font
					(size 1.27 1.27)
				)
				(justify mirror)
			)
		)
		(duplicate_pad_numbers_are_jumpers no)
		(fp_poly
			(pts
				(xy 0.4953 -0.2032) (xy -0.4953 -0.2032) (xy -0.4953 1.6002) (xy 0.4953 1.6002)
			)
			(stroke
				(width 0)
				(type default)
			)
			(fill no)
			(layer "B.CrtYd")
		)
		(fp_line
			(start -0.4953 -0.2032)
			(end -0.4953 1.6002)
			(stroke
				(width 0.1)
				(type default)
			)
			(layer "B.Fab")
		)
		(fp_line
			(start -0.4953 1.6002)
			(end 0.4953 1.6002)
			(stroke
				(width 0.1)
				(type default)
			)
			(layer "B.Fab")
		)
		(fp_line
			(start 0.4953 -0.2032)
			(end -0.4953 -0.2032)
			(stroke
				(width 0.1)
				(type default)
			)
			(layer "B.Fab")
		)
		(fp_line
			(start 0.4953 1.6002)
			(end 0.4953 -0.2032)
			(stroke
				(width 0.1)
				(type default)
			)
			(layer "B.Fab")
		)
		(pad "1" smd rect
			(at 0 0 180)
			(size 0.762 0.889)
			(layers "B.Cu" "B.Mask" "B.Paste")
			(net "P3V3_STBY")
		)
		(pad "2" smd rect
			(at 0 1.397 180)
			(size 0.762 0.889)
			(layers "B.Cu" "B.Mask" "B.Paste")
			(net "GND")
		)
		(zone
			(layer "B.Cu")
			(hatch none 0.5)
			(connect_pads
				(clearance 0)
			)
			(min_thickness 0.25)
			(keepout
				(tracks not_allowed)
				(vias allowed)
				(pads allowed)
				(copperpour not_allowed)
				(footprints allowed)
			)
			(placement
				(enabled no)
				(sheetname "")
			)
			(fill
				(thermal_gap 0.5)
				(thermal_bridge_width 0.5)
				(island_removal_mode 0)
			)
			(polygon
				(pts
					(xy 400.5072 -102.3874) (xy 399.7452 -102.3874) (xy 399.7452 -101.8794) (xy 400.5072 -101.8794)
				)
			)
		)
	)
	(footprint ""
		(layer "B.Cu")
		(at 382.3335 -44.196 90)
		(property "Reference" "R7E7"
			(at 0 0 90)
			(layer "B.SilkS")
			(hide yes)
			(effects
				(font
					(size 1.27 1.27)
				)
				(justify mirror)
			)
		)
		(property "Value" ""
			(at 0 0 90)
			(layer "B.Fab")
			(effects
				(font
					(size 1.27 1.27)
				)
				(justify mirror)
			)
		)
		(duplicate_pad_numbers_are_jumpers no)
		(fp_poly
			(pts
				(xy 0.2794 -0.1016) (xy -0.2794 -0.1016) (xy -0.2794 0.9906) (xy 0.2794 0.9906)
			)
			(stroke
				(width 0)
				(type default)
			)
			(fill no)
			(layer "B.CrtYd")
		)
		(fp_line
			(start 0.2794 -0.1016)
			(end 0.2794 0.9906)
			(stroke
				(width 0.1)
				(type default)
			)
			(layer "B.Fab")
		)
		(fp_line
			(start -0.2794 -0.1016)
			(end 0.2794 -0.1016)
			(stroke
				(width 0.1)
				(type default)
			)
			(layer "B.Fab")
		)
		(fp_line
			(start 0.2794 0.9906)
			(end -0.2794 0.9906)
			(stroke
				(width 0.1)
				(type default)
			)
			(layer "B.Fab")
		)
		(fp_line
			(start -0.2794 0.9906)
			(end -0.2794 -0.1016)
			(stroke
				(width 0.1)
				(type default)
			)
			(layer "B.Fab")
		)
		(pad "1" smd rect
			(at 0 0 270)
			(size 0.508 0.508)
			(layers "B.Cu" "B.Mask" "B.Paste")
			(net "P3V3")
		)
		(pad "2" smd rect
			(at 0 0.889 270)
			(size 0.508 0.508)
			(layers "B.Cu" "B.Mask" "B.Paste")
			(net "FM_SYS_THROTTLE_LVC3")
		)
		(zone
			(layer "B.Cu")
			(hatch none 0.5)
			(connect_pads
				(clearance 0)
			)
			(min_thickness 0.25)
			(keepout
				(tracks allowed)
				(vias not_allowed)
				(pads allowed)
				(copperpour not_allowed)
				(footprints allowed)
			)
			(placement
				(enabled no)
				(sheetname "")
			)
			(fill
				(thermal_gap 0.5)
				(thermal_bridge_width 0.5)
				(island_removal_mode 0)
			)
			(polygon
				(pts
					(xy 382.5875 -44.45) (xy 382.5875 -43.942) (xy 382.9685 -43.942) (xy 382.9685 -44.45)
				)
			)
		)
		(zone
			(layer "B.Cu")
			(hatch none 0.5)
			(connect_pads
				(clearance 0)
			)
			(min_thickness 0.25)
			(keepout
				(tracks not_allowed)
				(vias allowed)
				(pads allowed)
				(copperpour not_allowed)
				(footprints allowed)
			)
			(placement
				(enabled no)
				(sheetname "")
			)
			(fill
				(thermal_gap 0.5)
				(thermal_bridge_width 0.5)
				(island_removal_mode 0)
			)
			(polygon
				(pts
					(xy 382.9685 -44.45) (xy 382.9685 -43.942) (xy 382.5875 -43.942) (xy 382.5875 -44.45)
				)
			)
		)
	)
	(footprint ""
		(layer "B.Cu")
		(at 79.499968 -27.813 -90)
		(property "Reference" "C8T1"
			(at 0 0 90)
			(layer "B.SilkS")
			(hide yes)
			(effects
				(font
					(size 1.27 1.27)
				)
				(justify mirror)
			)
		)
		(property "Value" ""
			(at 0 0 90)
			(layer "B.Fab")
			(effects
				(font
					(size 1.27 1.27)
				)
				(justify mirror)
			)
		)
		(duplicate_pad_numbers_are_jumpers no)
		(fp_rect
			(start 0.500126 1.598422)
			(end -0.500126 -0.201422)
			(stroke
				(width 0)
				(type default)
			)
			(fill no)
			(layer "B.CrtYd")
		)
		(fp_line
			(start -0.500126 1.598422)
			(end 0.500126 1.598422)
			(stroke
				(width 0.1)
				(type default)
			)
			(layer "B.Fab")
		)
		(fp_line
			(start 0.500126 1.598422)
			(end 0.500126 -0.201422)
			(stroke
				(width 0.1)
				(type default)
			)
			(layer "B.Fab")
		)
		(fp_line
			(start -0.500126 -0.201422)
			(end -0.500126 1.598422)
			(stroke
				(width 0.1)
				(type default)
			)
			(layer "B.Fab")
		)
		(fp_line
			(start 0.500126 -0.201422)
			(end -0.500126 -0.201422)
			(stroke
				(width 0.1)
				(type default)
			)
			(layer "B.Fab")
		)
		(pad "1" smd rect
			(at 0 0 180)
			(size 0.889 0.9906)
			(layers "B.Cu" "B.Mask" "B.Paste")
			(net "PVDDQ_GHJ")
		)
		(pad "2" smd rect
			(at 0 1.397 180)
			(size 0.889 0.9906)
			(layers "B.Cu" "B.Mask" "B.Paste")
			(net "GND")
		)
		(zone
			(layer "B.Cu")
			(hatch none 0.5)
			(connect_pads
				(clearance 0)
			)
			(min_thickness 0.25)
			(keepout
				(tracks allowed)
				(vias not_allowed)
				(pads allowed)
				(copperpour not_allowed)
				(footprints allowed)
			)
			(placement
				(enabled no)
				(sheetname "")
			)
			(fill
				(thermal_gap 0.5)
				(thermal_bridge_width 0.5)
				(island_removal_mode 0)
			)
			(polygon
				(pts
					(xy 78.547468 -27.3177) (xy 79.055468 -27.3177) (xy 79.055468 -28.3083) (xy 78.547468 -28.3083)
				)
			)
		)
		(zone
			(layer "B.Cu")
			(hatch none 0.5)
			(connect_pads
				(clearance 0)
			)
			(min_thickness 0.25)
			(keepout
				(tracks not_allowed)
				(vias allowed)
				(pads allowed)
				(copperpour not_allowed)
				(footprints allowed)
			)
			(placement
				(enabled no)
				(sheetname "")
			)
			(fill
				(thermal_gap 0.5)
				(thermal_bridge_width 0.5)
				(island_removal_mode 0)
			)
			(polygon
				(pts
					(xy 78.547468 -27.3177) (xy 79.055468 -27.3177) (xy 79.055468 -28.3083) (xy 78.547468 -28.3083)
				)
			)
		)
	)
	(footprint ""
		(layer "B.Cu")
		(at 214.503 -86.4235)
		(property "Reference" "C6P3"
			(at 0 0 0)
			(layer "B.SilkS")
			(hide yes)
			(effects
				(font
					(size 1.27 1.27)
				)
				(justify mirror)
			)
		)
		(property "Value" ""
			(at 0 0 0)
			(layer "B.Fab")
			(effects
				(font
					(size 1.27 1.27)
				)
				(justify mirror)
			)
		)
		(duplicate_pad_numbers_are_jumpers no)
		(fp_poly
			(pts
				(xy 0.4953 -0.2032) (xy -0.4953 -0.2032) (xy -0.4953 1.6002) (xy 0.4953 1.6002)
			)
			(stroke
				(width 0)
				(type default)
			)
			(fill no)
			(layer "B.CrtYd")
		)
		(fp_line
			(start -0.4953 -0.2032)
			(end -0.4953 1.6002)
			(stroke
				(width 0.1)
				(type default)
			)
			(layer "B.Fab")
		)
		(fp_line
			(start -0.4953 1.6002)
			(end 0.4953 1.6002)
			(stroke
				(width 0.1)
				(type default)
			)
			(layer "B.Fab")
		)
		(fp_line
			(start 0.4953 -0.2032)
			(end -0.4953 -0.2032)
			(stroke
				(width 0.1)
				(type default)
			)
			(layer "B.Fab")
		)
		(fp_line
			(start 0.4953 1.6002)
			(end 0.4953 -0.2032)
			(stroke
				(width 0.1)
				(type default)
			)
			(layer "B.Fab")
		)
		(pad "1" smd rect
			(at 0 0 180)
			(size 0.762 0.889)
			(layers "B.Cu" "B.Mask" "B.Paste")
			(net "PVCCIN_CPU0")
		)
		(pad "2" smd rect
			(at 0 1.397 180)
			(size 0.762 0.889)
			(layers "B.Cu" "B.Mask" "B.Paste")
			(net "GND")
		)
		(zone
			(layer "B.Cu")
			(hatch none 0.5)
			(connect_pads
				(clearance 0)
			)
			(min_thickness 0.25)
			(keepout
				(tracks not_allowed)
				(vias allowed)
				(pads allowed)
				(copperpour not_allowed)
				(footprints allowed)
			)
			(placement
				(enabled no)
				(sheetname "")
			)
			(fill
				(thermal_gap 0.5)
				(thermal_bridge_width 0.5)
				(island_removal_mode 0)
			)
			(polygon
				(pts
					(xy 214.884 -85.979) (xy 214.122 -85.979) (xy 214.122 -85.471) (xy 214.884 -85.471)
				)
			)
		)
	)
	(footprint ""
		(layer "B.Cu")
		(at 375.270268 -47.566326 -90)
		(property "Reference" "R2T72"
			(at 0 0 90)
			(layer "B.SilkS")
			(hide yes)
			(effects
				(font
					(size 1.27 1.27)
				)
				(justify mirror)
			)
		)
		(property "Value" ""
			(at 0 0 90)
			(layer "B.Fab")
			(effects
				(font
					(size 1.27 1.27)
				)
				(justify mirror)
			)
		)
		(duplicate_pad_numbers_are_jumpers no)
		(fp_poly
			(pts
				(xy 0.2794 -0.1016) (xy -0.2794 -0.1016) (xy -0.2794 0.9906) (xy 0.2794 0.9906)
			)
			(stroke
				(width 0)
				(type default)
			)
			(fill no)
			(layer "B.CrtYd")
		)
		(fp_line
			(start -0.2794 0.9906)
			(end -0.2794 -0.1016)
			(stroke
				(width 0.1)
				(type default)
			)
			(layer "B.Fab")
		)
		(fp_line
			(start 0.2794 0.9906)
			(end -0.2794 0.9906)
			(stroke
				(width 0.1)
				(type default)
			)
			(layer "B.Fab")
		)
		(fp_line
			(start -0.2794 -0.1016)
			(end 0.2794 -0.1016)
			(stroke
				(width 0.1)
				(type default)
			)
			(layer "B.Fab")
		)
		(fp_line
			(start 0.2794 -0.1016)
			(end 0.2794 0.9906)
			(stroke
				(width 0.1)
				(type default)
			)
			(layer "B.Fab")
		)
		(pad "1" smd rect
			(at 0 0 90)
			(size 0.508 0.508)
			(layers "B.Cu" "B.Mask" "B.Paste")
			(net "PVCCIO_CPU0")
		)
		(pad "2" smd rect
			(at 0 0.889 90)
			(size 0.508 0.508)
			(layers "B.Cu" "B.Mask" "B.Paste")
			(net "H_CPU0_PROCHOT_G_N")
		)
		(zone
			(layer "B.Cu")
			(hatch none 0.5)
			(connect_pads
				(clearance 0)
			)
			(min_thickness 0.25)
			(keepout
				(tracks not_allowed)
				(vias allowed)
				(pads allowed)
				(copperpour not_allowed)
				(footprints allowed)
			)
			(placement
				(enabled no)
				(sheetname "")
			)
			(fill
				(thermal_gap 0.5)
				(thermal_bridge_width 0.5)
				(island_removal_mode 0)
			)
			(polygon
				(pts
					(xy 374.635268 -47.312326) (xy 374.635268 -47.820326) (xy 375.016268 -47.820326) (xy 375.016268 -47.312326)
				)
			)
		)
		(zone
			(layer "B.Cu")
			(hatch none 0.5)
			(connect_pads
				(clearance 0)
			)
			(min_thickness 0.25)
			(keepout
				(tracks allowed)
				(vias not_allowed)
				(pads allowed)
				(copperpour not_allowed)
				(footprints allowed)
			)
			(placement
				(enabled no)
				(sheetname "")
			)
			(fill
				(thermal_gap 0.5)
				(thermal_bridge_width 0.5)
				(island_removal_mode 0)
			)
			(polygon
				(pts
					(xy 375.016268 -47.312326) (xy 375.016268 -47.820326) (xy 374.635268 -47.820326) (xy 374.635268 -47.312326)
				)
			)
		)
	)
	(footprint ""
		(layer "B.Cu")
		(at 343.063068 -77.694536 180)
		(property "Reference" "C3P17"
			(at 0 0 0)
			(layer "B.SilkS")
			(hide yes)
			(effects
				(font
					(size 1.27 1.27)
				)
				(justify mirror)
			)
		)
		(property "Value" ""
			(at 0 0 0)
			(layer "B.Fab")
			(effects
				(font
					(size 1.27 1.27)
				)
				(justify mirror)
			)
		)
		(duplicate_pad_numbers_are_jumpers no)
		(fp_poly
			(pts
				(xy -0.3048 -0.1016) (xy -0.3048 0.9906) (xy 0.3048 0.9906) (xy 0.3048 -0.1016)
			)
			(stroke
				(width 0)
				(type default)
			)
			(fill no)
			(layer "B.CrtYd")
		)
		(fp_line
			(start 0.3048 0.9906)
			(end -0.3048 0.9906)
			(stroke
				(width 0.1)
				(type default)
			)
			(layer "B.Fab")
		)
		(fp_line
			(start 0.3048 -0.1016)
			(end 0.3048 0.9906)
			(stroke
				(width 0.1)
				(type default)
			)
			(layer "B.Fab")
		)
		(fp_line
			(start -0.3048 0.9906)
			(end -0.3048 -0.1016)
			(stroke
				(width 0.1)
				(type default)
			)
			(layer "B.Fab")
		)
		(fp_line
			(start -0.3048 -0.1016)
			(end 0.3048 -0.1016)
			(stroke
				(width 0.1)
				(type default)
			)
			(layer "B.Fab")
		)
		(pad "1" smd rect
			(at 0 0)
			(size 0.508 0.508)
			(layers "B.Cu" "B.Mask" "B.Paste")
			(net "P3E_CPU0_PE1_SS_TXN<1>")
		)
		(pad "2" smd rect
			(at 0 0.889)
			(size 0.508 0.508)
			(layers "B.Cu" "B.Mask" "B.Paste")
			(net "P3E_CPU0_PE1_PCH_TXN<1>")
		)
		(zone
			(layer "B.Cu")
			(hatch none 0.5)
			(connect_pads
				(clearance 0)
			)
			(min_thickness 0.25)
			(keepout
				(tracks not_allowed)
				(vias allowed)
				(pads allowed)
				(copperpour not_allowed)
				(footprints allowed)
			)
			(placement
				(enabled no)
				(sheetname "")
			)
			(fill
				(thermal_gap 0.5)
				(thermal_bridge_width 0.5)
				(island_removal_mode 0)
			)
			(polygon
				(pts
					(xy 342.809068 -78.329536) (xy 343.317068 -78.329536) (xy 343.317068 -77.948536) (xy 342.809068 -77.948536)
				)
			)
		)
		(zone
			(layer "B.Cu")
			(hatch none 0.5)
			(connect_pads
				(clearance 0)
			)
			(min_thickness 0.25)
			(keepout
				(tracks allowed)
				(vias not_allowed)
				(pads allowed)
				(copperpour not_allowed)
				(footprints allowed)
			)
			(placement
				(enabled no)
				(sheetname "")
			)
			(fill
				(thermal_gap 0.5)
				(thermal_bridge_width 0.5)
				(island_removal_mode 0)
			)
			(polygon
				(pts
					(xy 342.809068 -77.948536) (xy 343.317068 -77.948536) (xy 343.317068 -78.329536) (xy 342.809068 -78.329536)
				)
			)
		)
	)
	(footprint ""
		(layer "B.Cu")
		(at 320.194432 -145.034 90)
		(property "Reference" "C4L3"
			(at 0 0 90)
			(layer "B.SilkS")
			(hide yes)
			(effects
				(font
					(size 1.27 1.27)
				)
				(justify mirror)
			)
		)
		(property "Value" ""
			(at 0 0 90)
			(layer "B.Fab")
			(effects
				(font
					(size 1.27 1.27)
				)
				(justify mirror)
			)
		)
		(duplicate_pad_numbers_are_jumpers no)
		(fp_poly
			(pts
				(xy 0.4953 -0.2032) (xy -0.4953 -0.2032) (xy -0.4953 1.6002) (xy 0.4953 1.6002)
			)
			(stroke
				(width 0)
				(type default)
			)
			(fill no)
			(layer "B.CrtYd")
		)
		(fp_line
			(start 0.4953 -0.2032)
			(end -0.4953 -0.2032)
			(stroke
				(width 0.1)
				(type default)
			)
			(layer "B.Fab")
		)
		(fp_line
			(start -0.4953 -0.2032)
			(end -0.4953 1.6002)
			(stroke
				(width 0.1)
				(type default)
			)
			(layer "B.Fab")
		)
		(fp_line
			(start 0.4953 1.6002)
			(end 0.4953 -0.2032)
			(stroke
				(width 0.1)
				(type default)
			)
			(layer "B.Fab")
		)
		(fp_line
			(start -0.4953 1.6002)
			(end 0.4953 1.6002)
			(stroke
				(width 0.1)
				(type default)
			)
			(layer "B.Fab")
		)
		(pad "1" smd rect
			(at 0 0 270)
			(size 0.762 0.889)
			(layers "B.Cu" "B.Mask" "B.Paste")
			(net "PVPP_DEF")
		)
		(pad "2" smd rect
			(at 0 1.397 270)
			(size 0.762 0.889)
			(layers "B.Cu" "B.Mask" "B.Paste")
			(net "GND")
		)
		(zone
			(layer "B.Cu")
			(hatch none 0.5)
			(connect_pads
				(clearance 0)
			)
			(min_thickness 0.25)
			(keepout
				(tracks not_allowed)
				(vias allowed)
				(pads allowed)
				(copperpour not_allowed)
				(footprints allowed)
			)
			(placement
				(enabled no)
				(sheetname "")
			)
			(fill
				(thermal_gap 0.5)
				(thermal_bridge_width 0.5)
				(island_removal_mode 0)
			)
			(polygon
				(pts
					(xy 320.638932 -145.415) (xy 320.638932 -144.653) (xy 321.146932 -144.653) (xy 321.146932 -145.415)
				)
			)
		)
	)
)
